(kicad_pcb
	(version 20260206)
	(generator "pcbnew")
	(generator_version "10.0")
	(general
		(thickness 1.6)
		(legacy_teardrops no)
	)
	(paper "A4")
	(title_block
		(title "Wiwynn_Tioga_Pass_MB.brd")
		(comment 1 "Tioga Pass / footprint 2254 of 4770 (U5D1), pads 303-410 of 3647")
	)
	(layers
		(0 "F.Cu" signal "TOP")
		(4 "In1.Cu" signal "L2GND")
		(6 "In2.Cu" signal "L3")
		(8 "In3.Cu" signal "L4GND")
		(10 "In4.Cu" signal "L5")
		(12 "In5.Cu" signal "L6GND")
		(14 "In6.Cu" signal "L7VCC")
		(16 "In7.Cu" signal "L8VCC")
		(18 "In8.Cu" signal "L9GND")
		(20 "In9.Cu" signal "L10")
		(22 "In10.Cu" signal "L11GND")
		(24 "In11.Cu" signal "L12")
		(26 "In12.Cu" signal "L13GND")
		(2 "B.Cu" signal "BOTTOM")
		(9 "F.Adhes" user "F.Adhesive")
		(11 "B.Adhes" user "B.Adhesive")
		(13 "F.Paste" user "Package Geometry/Pastemask Top")
		(15 "B.Paste" user "Package Geometry/Pastemask Bottom")
		(5 "F.SilkS" user "Ref Des/Silkscreen Top")
		(7 "B.SilkS" user "Ref Des/Silkscreen Bottom")
		(1 "F.Mask" user "Board Geometry/Soldermask Top")
		(3 "B.Mask" user "Board Geometry/Soldermask Bottom")
		(17 "Dwgs.User" user "User.Drawings")
		(19 "Cmts.User" user "User.Comments")
		(21 "Eco1.User" user "User.Eco1")
		(23 "Eco2.User" user "User.Eco2")
		(25 "Edge.Cuts" user "Board Geometry/Outline")
		(27 "Margin" user)
		(31 "F.CrtYd" user "Package Geometry/Place Bound Top")
		(29 "B.CrtYd" user "Package Geometry/Place Bound Bottom")
		(35 "F.Fab" user "Ref Des/Assembly Top")
		(33 "B.Fab" user "Ref Des/Assembly Bottom")
	)
	(footprint ""
		(layer "F.Cu")
		(at 270.000222 -76.550012 180)
		(property "Reference" "U5D1"
			(at 19.124422 31.601918 0)
			(unlocked yes)
			(layer "F.SilkS")
			(effects
				(font
					(size 0.7874 0.5842)
					(thickness 0.1524)
				)
			)
		)
		(property "Value" ""
			(at 0 0 180)
			(layer "F.Fab")
			(effects
				(font
					(size 1.27 1.27)
				)
			)
		)
		(duplicate_pad_numbers_are_jumpers no)
		(pad "AG64" smd circle
			(at 18.363438 -14.025372)
			(size 0.4318 0.4318)
			(layers "F.Cu" "F.Mask" "F.Paste")
			(net "GND")
		)
		(pad "AG66" smd circle
			(at 20.080478 -14.025372)
			(size 0.4318 0.4318)
			(layers "F.Cu" "F.Mask" "F.Paste")
			(net "M_A_ECC<7>")
		)
		(pad "AG68" smd circle
			(at 21.797518 -14.025372)
			(size 0.4318 0.4318)
			(layers "F.Cu" "F.Mask" "F.Paste")
			(net "M_A_ECC<1>")
		)
		(pad "AG70" smd circle
			(at 23.514558 -14.025372)
			(size 0.4318 0.4318)
			(layers "F.Cu" "F.Mask" "F.Paste")
			(net "GND")
		)
		(pad "AG72" smd circle
			(at 25.231598 -14.025372)
			(size 0.4318 0.4318)
			(layers "F.Cu" "F.Mask" "F.Paste")
			(net "TP_CPU0_RSVD_234")
		)
		(pad "AG74" smd circle
			(at 26.948384 -14.025372)
			(size 0.4318 0.4318)
			(layers "F.Cu" "F.Mask" "F.Paste")
			(net "GND")
		)
		(pad "AG76" smd circle
			(at 28.665424 -14.025372)
			(size 0.4318 0.4318)
			(layers "F.Cu" "F.Mask" "F.Paste")
			(net "GND")
		)
		(pad "AG78" smd circle
			(at 30.382464 -14.025372)
			(size 0.4318 0.4318)
			(layers "F.Cu" "F.Mask" "F.Paste")
			(net "GND")
		)
		(pad "AG80" smd circle
			(at 32.099504 -14.025372)
			(size 0.4318 0.4318)
			(layers "F.Cu" "F.Mask" "F.Paste")
			(net "GND")
		)
		(pad "AG82" smd circle
			(at 33.816544 -14.025372)
			(size 0.4318 0.4318)
			(layers "F.Cu" "F.Mask" "F.Paste")
			(net "M_B_DQS_DN<10>")
		)
		(pad "AG84" smd circle
			(at 35.533584 -14.025372)
			(size 0.4318 0.4318)
			(layers "F.Cu" "F.Mask" "F.Paste")
			(net "M_A_DQ<7>")
		)
		(pad "AG86" smd custom
			(at 37.250624 -14.025372 270)
			(size 0.10795 0.10795)
			(layers "F.Cu" "F.Mask" "F.Paste")
			(net "M_A_DQ<6>")
			(options
				(clearance outline)
				(anchor circle)
			)
			(primitives
				(gr_poly
					(pts
						(arc
							(start 0.2159 -0.0381)
							(mid 0 -0.254)
							(end -0.2159 -0.0381)
						)
						(arc
							(start -0.2159 0.0381)
							(mid 0 0.254)
							(end 0.2159 0.0381)
						)
					)
					(width 0)
					(fill yes)
				)
			)
		)
		(pad "AH1" smd custom
			(at -37.250624 -11.730228 90)
			(size 0.10795 0.10795)
			(layers "F.Cu" "F.Mask" "F.Paste")
			(net "GND")
			(options
				(clearance outline)
				(anchor circle)
			)
			(primitives
				(gr_poly
					(pts
						(arc
							(start 0.2159 -0.0381)
							(mid 0 -0.254)
							(end -0.2159 -0.0381)
						)
						(arc
							(start -0.2159 0.0381)
							(mid 0 0.254)
							(end 0.2159 0.0381)
						)
					)
					(width 0)
					(fill yes)
				)
			)
		)
		(pad "AH3" smd circle
			(at -35.533584 -11.730228)
			(size 0.4318 0.4318)
			(layers "F.Cu" "F.Mask" "F.Paste")
			(net "UPI_CPU0_CPU1_P0P0_DN<11>")
		)
		(pad "AH5" smd circle
			(at -33.816544 -11.730228)
			(size 0.4318 0.4318)
			(layers "F.Cu" "F.Mask" "F.Paste")
			(net "GND")
		)
		(pad "AH7" smd circle
			(at -32.099504 -11.730228)
			(size 0.4318 0.4318)
			(layers "F.Cu" "F.Mask" "F.Paste")
			(net "UPI_CPU1_CPU0_P0P0_DP<13>")
		)
		(pad "AH9" smd circle
			(at -30.382464 -11.730228)
			(size 0.4318 0.4318)
			(layers "F.Cu" "F.Mask" "F.Paste")
			(net "PVCCIO_CPU0")
		)
		(pad "AH11" smd circle
			(at -28.665424 -11.730228)
			(size 0.4318 0.4318)
			(layers "F.Cu" "F.Mask" "F.Paste")
			(net "XDP_CPU_MBP1_N")
		)
		(pad "AH13" smd circle
			(at -26.948384 -11.730228)
			(size 0.4318 0.4318)
			(layers "F.Cu" "F.Mask" "F.Paste")
			(net "H_CPU0_MEMABC_MEMHOT_G_N")
		)
		(pad "AH15" smd circle
			(at -25.231598 -11.730228)
			(size 0.4318 0.4318)
			(layers "F.Cu" "F.Mask" "F.Paste")
			(net "TP_CPU0_RSVD_233")
		)
		(pad "AH19" smd circle
			(at -21.797518 -11.730228)
			(size 0.4318 0.4318)
			(layers "F.Cu" "F.Mask" "F.Paste")
			(net "TP_CPU0_RSVD_232")
		)
		(pad "AH21" smd circle
			(at -20.080478 -11.730228)
			(size 0.4318 0.4318)
			(layers "F.Cu" "F.Mask" "F.Paste")
			(net "GND")
		)
		(pad "AH23" smd circle
			(at -18.363438 -11.730228)
			(size 0.4318 0.4318)
			(layers "F.Cu" "F.Mask" "F.Paste")
			(net "M_C_DQ<63>")
		)
		(pad "AH25" smd circle
			(at -16.646398 -11.730228)
			(size 0.4318 0.4318)
			(layers "F.Cu" "F.Mask" "F.Paste")
			(net "M_C_DQ<57>")
		)
		(pad "AH27" smd circle
			(at -14.929612 -11.730228)
			(size 0.4318 0.4318)
			(layers "F.Cu" "F.Mask" "F.Paste")
			(net "GND")
		)
		(pad "AH29" smd circle
			(at -13.212572 -11.730228)
			(size 0.4318 0.4318)
			(layers "F.Cu" "F.Mask" "F.Paste")
			(net "M_C_DQ<55>")
		)
		(pad "AH31" smd circle
			(at -11.495532 -11.730228)
			(size 0.4318 0.4318)
			(layers "F.Cu" "F.Mask" "F.Paste")
			(net "M_C_DQ<49>")
		)
		(pad "AH33" smd circle
			(at -9.778492 -11.730228)
			(size 0.4318 0.4318)
			(layers "F.Cu" "F.Mask" "F.Paste")
			(net "GND")
		)
		(pad "AH35" smd circle
			(at -8.061452 -11.730228)
			(size 0.4318 0.4318)
			(layers "F.Cu" "F.Mask" "F.Paste")
			(net "GND")
		)
		(pad "AH37" smd circle
			(at -6.344412 -11.730228)
			(size 0.4318 0.4318)
			(layers "F.Cu" "F.Mask" "F.Paste")
			(net "PVCCIN_CPU0")
		)
		(pad "AH39" smd circle
			(at -4.627626 -11.730228)
			(size 0.4318 0.4318)
			(layers "F.Cu" "F.Mask" "F.Paste")
			(net "PVCCIN_CPU0")
		)
		(pad "AH41" smd circle
			(at -2.910586 -11.730228)
			(size 0.4318 0.4318)
			(layers "F.Cu" "F.Mask" "F.Paste")
			(net "PVCCIN_CPU0")
		)
		(pad "AH45" smd circle
			(at 2.052066 -13.530326)
			(size 0.508 0.508)
			(layers "F.Cu" "F.Mask" "F.Paste")
			(net "GND")
		)
		(pad "AH47" smd circle
			(at 3.769106 -13.530326)
			(size 0.4318 0.4318)
			(layers "F.Cu" "F.Mask" "F.Paste")
			(net "GND")
		)
		(pad "AH49" smd circle
			(at 5.485892 -13.530326)
			(size 0.4318 0.4318)
			(layers "F.Cu" "F.Mask" "F.Paste")
			(net "GND")
		)
		(pad "AH51" smd circle
			(at 7.202932 -13.530326)
			(size 0.4318 0.4318)
			(layers "F.Cu" "F.Mask" "F.Paste")
			(net "GND")
		)
		(pad "AH53" smd circle
			(at 8.919972 -13.530326)
			(size 0.4318 0.4318)
			(layers "F.Cu" "F.Mask" "F.Paste")
			(net "GND")
		)
		(pad "AH55" smd circle
			(at 10.637012 -13.530326)
			(size 0.4318 0.4318)
			(layers "F.Cu" "F.Mask" "F.Paste")
			(net "TP_CPU0_RSVD_231")
		)
		(pad "AH57" smd circle
			(at 12.354052 -13.530326)
			(size 0.4318 0.4318)
			(layers "F.Cu" "F.Mask" "F.Paste")
			(net "TP_CPU0_RSVD_230")
		)
		(pad "AH59" smd circle
			(at 14.071092 -13.530326)
			(size 0.4318 0.4318)
			(layers "F.Cu" "F.Mask" "F.Paste")
			(net "GND")
		)
		(pad "AH61" smd circle
			(at 15.787878 -13.530326)
			(size 0.4318 0.4318)
			(layers "F.Cu" "F.Mask" "F.Paste")
			(net "GND")
		)
		(pad "AH63" smd circle
			(at 17.504918 -13.530326)
			(size 0.4318 0.4318)
			(layers "F.Cu" "F.Mask" "F.Paste")
			(net "M_C_CPU_VREF")
		)
		(pad "AH65" smd circle
			(at 19.221958 -13.530326)
			(size 0.4318 0.4318)
			(layers "F.Cu" "F.Mask" "F.Paste")
			(net "GND")
		)
		(pad "AH67" smd circle
			(at 20.938998 -13.530326)
			(size 0.4318 0.4318)
			(layers "F.Cu" "F.Mask" "F.Paste")
			(net "M_A_DQS_DN<8>")
		)
		(pad "AH69" smd circle
			(at 22.656038 -13.530326)
			(size 0.4318 0.4318)
			(layers "F.Cu" "F.Mask" "F.Paste")
			(net "GND")
		)
		(pad "AH71" smd circle
			(at 24.373078 -13.530326)
			(size 0.4318 0.4318)
			(layers "F.Cu" "F.Mask" "F.Paste")
			(net "TP_CPU0_RSVD_229")
		)
		(pad "AH73" smd circle
			(at 26.090118 -13.530326)
			(size 0.4318 0.4318)
			(layers "F.Cu" "F.Mask" "F.Paste")
			(net "TP_CPU0_RSVD_228")
		)
		(pad "AH75" smd circle
			(at 27.806904 -13.530326)
			(size 0.4318 0.4318)
			(layers "F.Cu" "F.Mask" "F.Paste")
			(net "GND")
		)
		(pad "AH77" smd circle
			(at 29.523944 -13.530326)
			(size 0.4318 0.4318)
			(layers "F.Cu" "F.Mask" "F.Paste")
			(net "GND")
		)
		(pad "AH79" smd circle
			(at 31.240984 -13.530326)
			(size 0.4318 0.4318)
			(layers "F.Cu" "F.Mask" "F.Paste")
			(net "M_B_DQ<13>")
		)
		(pad "AH81" smd circle
			(at 32.958024 -13.530326)
			(size 0.4318 0.4318)
			(layers "F.Cu" "F.Mask" "F.Paste")
			(net "M_B_DQ<8>")
		)
		(pad "AH83" smd circle
			(at 34.675064 -13.530326)
			(size 0.4318 0.4318)
			(layers "F.Cu" "F.Mask" "F.Paste")
			(net "GND")
		)
		(pad "AH85" smd circle
			(at 36.392104 -13.530326)
			(size 0.4318 0.4318)
			(layers "F.Cu" "F.Mask" "F.Paste")
			(net "M_A_DQS_DP<0>")
		)
		(pad "AJ2" smd circle
			(at -36.392104 -11.234674)
			(size 0.4318 0.4318)
			(layers "F.Cu" "F.Mask" "F.Paste")
			(net "UPI_CPU0_CPU1_P0P0_DP<11>")
		)
		(pad "AJ4" smd circle
			(at -34.675064 -11.234674)
			(size 0.4318 0.4318)
			(layers "F.Cu" "F.Mask" "F.Paste")
			(net "GND")
		)
		(pad "AJ6" smd circle
			(at -32.958024 -11.234674)
			(size 0.4318 0.4318)
			(layers "F.Cu" "F.Mask" "F.Paste")
			(net "UPI_CPU1_CPU0_P0P0_DN<13>")
		)
		(pad "AJ8" smd circle
			(at -31.240984 -11.234674)
			(size 0.4318 0.4318)
			(layers "F.Cu" "F.Mask" "F.Paste")
			(net "GND")
		)
		(pad "AJ10" smd circle
			(at -29.523944 -11.234674)
			(size 0.4318 0.4318)
			(layers "F.Cu" "F.Mask" "F.Paste")
			(net "XDP_CPU_MBP0_N")
		)
		(pad "AJ12" smd circle
			(at -27.806904 -11.234674)
			(size 0.4318 0.4318)
			(layers "F.Cu" "F.Mask" "F.Paste")
			(net "H_CPU0_ERR0_G_N")
		)
		(pad "AJ14" smd circle
			(at -26.090118 -11.234674)
			(size 0.4318 0.4318)
			(layers "F.Cu" "F.Mask" "F.Paste")
			(net "PD_CPU0_EAR_N")
		)
		(pad "AJ18" smd circle
			(at -22.656038 -11.234674)
			(size 0.4318 0.4318)
			(layers "F.Cu" "F.Mask" "F.Paste")
			(net "SMB_DDR_ABC_SCL_G_R")
		)
		(pad "AJ20" smd circle
			(at -20.938998 -11.234674)
			(size 0.4318 0.4318)
			(layers "F.Cu" "F.Mask" "F.Paste")
			(net "TP_CPU0_RSVD_227")
		)
		(pad "AJ22" smd circle
			(at -19.221958 -11.234674)
			(size 0.4318 0.4318)
			(layers "F.Cu" "F.Mask" "F.Paste")
			(net "GND")
		)
		(pad "AJ24" smd circle
			(at -17.504918 -11.234674)
			(size 0.4318 0.4318)
			(layers "F.Cu" "F.Mask" "F.Paste")
			(net "M_C_DQS_DN<7>")
		)
		(pad "AJ26" smd circle
			(at -15.787878 -11.234674)
			(size 0.4318 0.4318)
			(layers "F.Cu" "F.Mask" "F.Paste")
			(net "GND")
		)
		(pad "AJ28" smd circle
			(at -14.071092 -11.234674)
			(size 0.4318 0.4318)
			(layers "F.Cu" "F.Mask" "F.Paste")
			(net "GND")
		)
		(pad "AJ30" smd circle
			(at -12.354052 -11.234674)
			(size 0.4318 0.4318)
			(layers "F.Cu" "F.Mask" "F.Paste")
			(net "M_C_DQS_DN<6>")
		)
		(pad "AJ32" smd circle
			(at -10.637012 -11.234674)
			(size 0.4318 0.4318)
			(layers "F.Cu" "F.Mask" "F.Paste")
			(net "GND")
		)
		(pad "AJ34" smd circle
			(at -8.919972 -11.234674)
			(size 0.4318 0.4318)
			(layers "F.Cu" "F.Mask" "F.Paste")
			(net "GND")
		)
		(pad "AJ36" smd circle
			(at -7.202932 -11.234674)
			(size 0.4318 0.4318)
			(layers "F.Cu" "F.Mask" "F.Paste")
			(net "PVCCIN_CPU0")
		)
		(pad "AJ46" smd circle
			(at 2.910586 -13.034772)
			(size 0.4318 0.4318)
			(layers "F.Cu" "F.Mask" "F.Paste")
			(net "GND")
		)
		(pad "AJ48" smd circle
			(at 4.627626 -13.034772)
			(size 0.4318 0.4318)
			(layers "F.Cu" "F.Mask" "F.Paste")
			(net "GND")
		)
		(pad "AJ50" smd circle
			(at 6.344412 -13.034772)
			(size 0.4318 0.4318)
			(layers "F.Cu" "F.Mask" "F.Paste")
			(net "GND")
		)
		(pad "AJ52" smd circle
			(at 8.061452 -13.034772)
			(size 0.4318 0.4318)
			(layers "F.Cu" "F.Mask" "F.Paste")
			(net "GND")
		)
		(pad "AJ54" smd circle
			(at 9.778492 -13.034772)
			(size 0.4318 0.4318)
			(layers "F.Cu" "F.Mask" "F.Paste")
			(net "GND")
		)
		(pad "AJ56" smd circle
			(at 11.495532 -13.034772)
			(size 0.4318 0.4318)
			(layers "F.Cu" "F.Mask" "F.Paste")
			(net "TP_CPU0_RSVD_226")
		)
		(pad "AJ58" smd circle
			(at 13.212572 -13.034772)
			(size 0.4318 0.4318)
			(layers "F.Cu" "F.Mask" "F.Paste")
			(net "TP_CPU0_RSVD_225")
		)
		(pad "AJ60" smd circle
			(at 14.929612 -13.034772)
			(size 0.4318 0.4318)
			(layers "F.Cu" "F.Mask" "F.Paste")
			(net "TP_CPU0_RSVD_224")
		)
		(pad "AJ62" smd circle
			(at 16.646398 -13.034772)
			(size 0.4318 0.4318)
			(layers "F.Cu" "F.Mask" "F.Paste")
			(net "TP_CPU0_RSVD_223")
		)
		(pad "AJ64" smd circle
			(at 18.363438 -13.034772)
			(size 0.4318 0.4318)
			(layers "F.Cu" "F.Mask" "F.Paste")
			(net "M_A_CPU_VREF")
		)
		(pad "AJ66" smd circle
			(at 20.080478 -13.034772)
			(size 0.4318 0.4318)
			(layers "F.Cu" "F.Mask" "F.Paste")
			(net "GND")
		)
		(pad "AJ68" smd circle
			(at 21.797518 -13.034772)
			(size 0.4318 0.4318)
			(layers "F.Cu" "F.Mask" "F.Paste")
			(net "GND")
		)
		(pad "AJ70" smd circle
			(at 23.514558 -13.034772)
			(size 0.4318 0.4318)
			(layers "F.Cu" "F.Mask" "F.Paste")
			(net "TP_CPU0_RSVD_222")
		)
		(pad "AJ74" smd circle
			(at 26.948384 -13.034772)
			(size 0.4318 0.4318)
			(layers "F.Cu" "F.Mask" "F.Paste")
			(net "GND")
		)
		(pad "AJ76" smd circle
			(at 28.665424 -13.034772)
			(size 0.4318 0.4318)
			(layers "F.Cu" "F.Mask" "F.Paste")
			(net "M_C_DQ<3>")
		)
		(pad "AJ78" smd circle
			(at 30.382464 -13.034772)
			(size 0.4318 0.4318)
			(layers "F.Cu" "F.Mask" "F.Paste")
			(net "GND")
		)
		(pad "AJ80" smd circle
			(at 32.099504 -13.034772)
			(size 0.4318 0.4318)
			(layers "F.Cu" "F.Mask" "F.Paste")
			(net "M_B_DQ<12>")
		)
		(pad "AJ82" smd circle
			(at 33.816544 -13.034772)
			(size 0.4318 0.4318)
			(layers "F.Cu" "F.Mask" "F.Paste")
			(net "GND")
		)
		(pad "AJ84" smd circle
			(at 35.533584 -13.034772)
			(size 0.4318 0.4318)
			(layers "F.Cu" "F.Mask" "F.Paste")
			(net "M_A_DQS_DN<0>")
		)
		(pad "AJ86" smd custom
			(at 37.250624 -13.034772 270)
			(size 0.10795 0.10795)
			(layers "F.Cu" "F.Mask" "F.Paste")
			(net "GND")
			(options
				(clearance outline)
				(anchor circle)
			)
			(primitives
				(gr_poly
					(pts
						(arc
							(start 0.2159 -0.0381)
							(mid 0 -0.254)
							(end -0.2159 -0.0381)
						)
						(arc
							(start -0.2159 0.0381)
							(mid 0 0.254)
							(end 0.2159 0.0381)
						)
					)
					(width 0)
					(fill yes)
				)
			)
		)
		(pad "AK1" smd custom
			(at -37.250624 -10.739628 90)
			(size 0.10795 0.10795)
			(layers "F.Cu" "F.Mask" "F.Paste")
			(net "UPI_CPU0_CPU1_P0P0_DP<10>")
			(options
				(clearance outline)
				(anchor circle)
			)
			(primitives
				(gr_poly
					(pts
						(arc
							(start 0.2159 -0.0381)
							(mid 0 -0.254)
							(end -0.2159 -0.0381)
						)
						(arc
							(start -0.2159 0.0381)
							(mid 0 0.254)
							(end 0.2159 0.0381)
						)
					)
					(width 0)
					(fill yes)
				)
			)
		)
		(pad "AK3" smd circle
			(at -35.533584 -10.739628)
			(size 0.4318 0.4318)
			(layers "F.Cu" "F.Mask" "F.Paste")
			(net "UPI_CPU0_CPU1_P0P0_DP<9>")
		)
		(pad "AK5" smd circle
			(at -33.816544 -10.739628)
			(size 0.4318 0.4318)
			(layers "F.Cu" "F.Mask" "F.Paste")
			(net "UPI_CPU1_CPU0_P0P0_DP<12>")
		)
		(pad "AK7" smd circle
			(at -32.099504 -10.739628)
			(size 0.4318 0.4318)
			(layers "F.Cu" "F.Mask" "F.Paste")
			(net "UPI_CPU1_CPU0_P0P0_DN<11>")
		)
		(pad "AK9" smd circle
			(at -30.382464 -10.739628)
			(size 0.4318 0.4318)
			(layers "F.Cu" "F.Mask" "F.Paste")
			(net "GND")
		)
		(pad "AK11" smd circle
			(at -28.665424 -10.739628)
			(size 0.4318 0.4318)
			(layers "F.Cu" "F.Mask" "F.Paste")
			(net "H_CPU0_ERR1_G_N")
		)
		(pad "AK13" smd circle
			(at -26.948384 -10.739628)
			(size 0.4318 0.4318)
			(layers "F.Cu" "F.Mask" "F.Paste")
			(net "GND")
		)
		(pad "AK19" smd circle
			(at -21.797518 -10.739628)
			(size 0.4318 0.4318)
			(layers "F.Cu" "F.Mask" "F.Paste")
			(net "GND")
		)
		(pad "AK21" smd circle
			(at -20.080478 -10.739628)
			(size 0.4318 0.4318)
			(layers "F.Cu" "F.Mask" "F.Paste")
			(net "VSENSE_P1V8MCP_CPU0_SKT_VSEN")
		)
		(pad "AK23" smd circle
			(at -18.363438 -10.739628)
			(size 0.4318 0.4318)
			(layers "F.Cu" "F.Mask" "F.Paste")
			(net "GND")
		)
		(pad "AK25" smd circle
			(at -16.646398 -10.739628)
			(size 0.4318 0.4318)
			(layers "F.Cu" "F.Mask" "F.Paste")
			(net "GND")
		)
		(pad "AK27" smd circle
			(at -14.929612 -10.739628)
			(size 0.4318 0.4318)
			(layers "F.Cu" "F.Mask" "F.Paste")
			(net "CLK_322M_OSC_CPU0_RC_DP")
		)
		(pad "AK29" smd circle
			(at -13.212572 -10.739628)
			(size 0.4318 0.4318)
			(layers "F.Cu" "F.Mask" "F.Paste")
			(net "GND")
		)
		(pad "AK31" smd circle
			(at -11.495532 -10.739628)
			(size 0.4318 0.4318)
			(layers "F.Cu" "F.Mask" "F.Paste")
			(net "GND")
		)
		(pad "AK33" smd circle
			(at -9.778492 -10.739628)
			(size 0.4318 0.4318)
			(layers "F.Cu" "F.Mask" "F.Paste")
			(net "GND")
		)
		(pad "AK35" smd circle
			(at -8.061452 -10.739628)
			(size 0.4318 0.4318)
			(layers "F.Cu" "F.Mask" "F.Paste")
			(net "PVCCIN_CPU0")
		)
		(pad "AK45" smd circle
			(at 2.052066 -12.539726)
			(size 0.508 0.508)
			(layers "F.Cu" "F.Mask" "F.Paste")
			(net "PVCCIN_CPU0")
		)
		(pad "AK47" smd circle
			(at 3.769106 -12.539726)
			(size 0.4318 0.4318)
			(layers "F.Cu" "F.Mask" "F.Paste")
			(net "PVCCIN_CPU0")
		)
	)
)
